# T6G (Grand Teton) — schematic netlist excerpt (pin names and nets, part order shuffled) for the footprints in the layout excerpt that follows; sources: Cadence DE-HDL packaged netlist, KiCad conversion of 04192023_DAF0TMB3IC0_F0TG_MB_C_brd_V02_OCP.brd

PC6644_09P1_2  Q_CAP  2.2UF 10V 10% X6S  pkg C0402  page 365 : A = P0V9_RETIMER_CPU1_PVCC ; B = GND
PC229  Q_CAPP  390UF 2.5V 20% ALUM  pkg SMLF  page 208 : A = PVDD11_S3_P0 ; B = GND
R1018  Q_RES  1K 1% CHIP  pkg 0201LF  page 287 : A = RT_CPU0_P1_ADDR1 ; B = GND

(kicad_pcb
	(version 20260206)
	(generator "pcbnew")
	(generator_version "10.0")
	(general
		(thickness 1.6)
		(legacy_teardrops no)
	)
	(paper "A4")
	(title_block
		(title "04192023_DAF0TMB3IC0_F0TG_MB_C_brd_V02_OCP.brd")
		(comment 1 "Grand Teton / footprints 2093-2095 of 8354")
	)
	(layers
		(0 "F.Cu" signal "TOP")
		(4 "In1.Cu" signal "GND")
		(6 "In2.Cu" signal "IN1")
		(8 "In3.Cu" signal "GND1")
		(10 "In4.Cu" signal "IN2")
		(12 "In5.Cu" signal "GND2")
		(14 "In6.Cu" signal "IN3")
		(16 "In7.Cu" signal "GND3")
		(18 "In8.Cu" signal "VCC")
		(20 "In9.Cu" signal "VCC1")
		(22 "In10.Cu" signal "GND4")
		(24 "In11.Cu" signal "IN4")
		(26 "In12.Cu" signal "GND5")
		(28 "In13.Cu" signal "IN5")
		(30 "In14.Cu" signal "GND6")
		(32 "In15.Cu" signal "IN6")
		(34 "In16.Cu" signal "GND7")
		(2 "B.Cu" signal "BOTTOM")
		(9 "F.Adhes" user "F.Adhesive")
		(11 "B.Adhes" user "B.Adhesive")
		(13 "F.Paste" user "Package Geometry/Pastemask Top")
		(15 "B.Paste" user "Package Geometry/Pastemask Bottom")
		(5 "F.SilkS" user "Ref Des/Silkscreen Top")
		(7 "B.SilkS" user "Ref Des/Silkscreen Bottom")
		(1 "F.Mask" user "Board Geometry/Soldermask Top")
		(3 "B.Mask" user "Board Geometry/Soldermask Bottom")
		(17 "Dwgs.User" user "User.Drawings")
		(19 "Cmts.User" user "User.Comments")
		(21 "Eco1.User" user "User.Eco1")
		(23 "Eco2.User" user "User.Eco2")
		(25 "Edge.Cuts" user "Board Geometry/Outline")
		(27 "Margin" user)
		(31 "F.CrtYd" user "Package Geometry/Place Bound Top")
		(29 "B.CrtYd" user "Package Geometry/Place Bound Bottom")
		(35 "F.Fab" user "Ref Des/Assembly Top")
		(33 "B.Fab" user "Ref Des/Assembly Bottom")
	)
	(footprint ""
		(layer "F.Cu")
		(at 360.81589 -390.652)
		(property "Reference" "R1018"
			(at 0 0 0)
			(layer "F.SilkS")
			(hide yes)
			(effects
				(font
					(size 1.27 1.27)
				)
			)
		)
		(property "Value" ""
			(at 0 0 0)
			(layer "F.Fab")
			(effects
				(font
					(size 1.27 1.27)
				)
			)
		)
		(duplicate_pad_numbers_are_jumpers no)
		(fp_line
			(start -0.32512 -0.175006)
			(end 0.32512 -0.175006)
			(stroke
				(width 0.1)
				(type default)
			)
			(layer "F.Fab")
		)
		(fp_line
			(start -0.32512 0.175006)
			(end -0.32512 -0.175006)
			(stroke
				(width 0.1)
				(type default)
			)
			(layer "F.Fab")
		)
		(fp_line
			(start 0.32512 -0.175006)
			(end 0.32512 0.175006)
			(stroke
				(width 0.1)
				(type default)
			)
			(layer "F.Fab")
		)
		(fp_line
			(start 0.32512 0.175006)
			(end -0.32512 0.175006)
			(stroke
				(width 0.1)
				(type default)
			)
			(layer "F.Fab")
		)
		(pad "1" smd rect
			(at -0.2667 0)
			(size 0.3048 0.381)
			(layers "F.Cu" "F.Mask" "F.Paste")
			(net "RT_CPU0_P1_ADDR1")
		)
		(pad "2" smd rect
			(at 0.2667 0 180)
			(size 0.3048 0.381)
			(layers "F.Cu" "F.Mask" "F.Paste")
			(net "GND")
		)
	)
	(footprint ""
		(layer "F.Cu")
		(at 21.938996 -389.171434 -90)
		(property "Reference" "PC6644_09P1_2"
			(at 0 0 270)
			(layer "F.SilkS")
			(hide yes)
			(effects
				(font
					(size 1.27 1.27)
				)
			)
		)
		(property "Value" ""
			(at 0 0 270)
			(layer "F.Fab")
			(effects
				(font
					(size 1.27 1.27)
				)
			)
		)
		(duplicate_pad_numbers_are_jumpers no)
		(fp_line
			(start -0.7874 0.4064)
			(end -0.7874 -0.4064)
			(stroke
				(width 0.1524)
				(type default)
			)
			(layer "F.SilkS")
		)
		(fp_line
			(start 0.7874 0.4064)
			(end -0.7874 0.4064)
			(stroke
				(width 0.1524)
				(type default)
			)
			(layer "F.SilkS")
		)
		(fp_line
			(start -0.7874 -0.4064)
			(end 0.7874 -0.4064)
			(stroke
				(width 0.1524)
				(type default)
			)
			(layer "F.SilkS")
		)
		(fp_line
			(start 0.7874 -0.4064)
			(end 0.7874 0.4064)
			(stroke
				(width 0.1524)
				(type default)
			)
			(layer "F.SilkS")
		)
		(fp_line
			(start -0.67945 0.3048)
			(end -0.67945 -0.305054)
			(stroke
				(width 0.1)
				(type default)
			)
			(layer "F.Fab")
		)
		(fp_line
			(start -0.12065 0.3048)
			(end -0.67945 0.3048)
			(stroke
				(width 0.1)
				(type default)
			)
			(layer "F.Fab")
		)
		(fp_line
			(start 0.120396 0.3048)
			(end 0.120396 0.2794)
			(stroke
				(width 0.1)
				(type default)
			)
			(layer "F.Fab")
		)
		(fp_line
			(start 0.67945 0.3048)
			(end 0.120396 0.3048)
			(stroke
				(width 0.1)
				(type default)
			)
			(layer "F.Fab")
		)
		(fp_line
			(start -0.12065 0.2794)
			(end -0.12065 0.3048)
			(stroke
				(width 0.1)
				(type default)
			)
			(layer "F.Fab")
		)
		(fp_line
			(start 0.120396 0.2794)
			(end -0.12065 0.2794)
			(stroke
				(width 0.1)
				(type default)
			)
			(layer "F.Fab")
		)
		(fp_line
			(start -0.12065 -0.2794)
			(end 0.12065 -0.2794)
			(stroke
				(width 0.1)
				(type default)
			)
			(layer "F.Fab")
		)
		(fp_line
			(start 0.12065 -0.2794)
			(end 0.12065 -0.3048)
			(stroke
				(width 0.1)
				(type default)
			)
			(layer "F.Fab")
		)
		(fp_line
			(start 0.12065 -0.3048)
			(end 0.67945 -0.3048)
			(stroke
				(width 0.1)
				(type default)
			)
			(layer "F.Fab")
		)
		(fp_line
			(start 0.67945 -0.3048)
			(end 0.67945 0.3048)
			(stroke
				(width 0.1)
				(type default)
			)
			(layer "F.Fab")
		)
		(fp_line
			(start -0.67945 -0.305054)
			(end -0.12065 -0.305054)
			(stroke
				(width 0.1)
				(type default)
			)
			(layer "F.Fab")
		)
		(fp_line
			(start -0.12065 -0.305054)
			(end -0.12065 -0.2794)
			(stroke
				(width 0.1)
				(type default)
			)
			(layer "F.Fab")
		)
		(pad "1" smd circle
			(at -0.40005 0 270)
			(size 0 0)
			(layers "F.Cu" "F.Mask" "F.Paste")
			(net "P0V9_RETIMER_CPU1_PVCC")
		)
		(pad "2" smd circle
			(at 0.40005 0 270)
			(size 0 0)
			(layers "F.Cu" "F.Mask" "F.Paste")
			(net "GND")
		)
	)
	(footprint ""
		(layer "F.Cu")
		(at 432.783488 -332.63586 -90)
		(property "Reference" "PC229"
			(at -4.97332 -7.844536 90)
			(unlocked yes)
			(layer "F.SilkS")
			(effects
				(font
					(size 0.7874 0.5842)
					(thickness 0.1524)
				)
				(justify left)
			)
		)
		(property "Value" ""
			(at 0 0 270)
			(layer "F.Fab")
			(effects
				(font
					(size 1.27 1.27)
				)
			)
		)
		(duplicate_pad_numbers_are_jumpers no)
		(fp_line
			(start -1.988058 2.750058)
			(end 2.750058 2.750058)
			(stroke
				(width 0.1524)
				(type default)
			)
			(layer "F.SilkS")
		)
		(fp_line
			(start 2.750058 2.750058)
			(end 2.750058 0.9398)
			(stroke
				(width 0.1524)
				(type default)
			)
			(layer "F.SilkS")
		)
		(fp_line
			(start -2.750058 1.988058)
			(end -1.988058 2.750058)
			(stroke
				(width 0.1524)
				(type default)
			)
			(layer "F.SilkS")
		)
		(fp_line
			(start -2.750058 0.9398)
			(end -2.750058 1.988058)
			(stroke
				(width 0.1524)
				(type default)
			)
			(layer "F.SilkS")
		)
		(fp_line
			(start 2.750058 -0.9398)
			(end 2.750058 -2.750058)
			(stroke
				(width 0.1524)
				(type default)
			)
			(layer "F.SilkS")
		)
		(fp_line
			(start -2.750058 -1.988058)
			(end -2.750058 -0.9398)
			(stroke
				(width 0.1524)
				(type default)
			)
			(layer "F.SilkS")
		)
		(fp_line
			(start -1.988058 -2.750058)
			(end -2.750058 -1.988058)
			(stroke
				(width 0.1524)
				(type default)
			)
			(layer "F.SilkS")
		)
		(fp_line
			(start 2.750058 -2.750058)
			(end -1.988058 -2.750058)
			(stroke
				(width 0.1524)
				(type default)
			)
			(layer "F.SilkS")
		)
		(fp_line
			(start -2.750058 2.750058)
			(end 2.750058 2.750058)
			(stroke
				(width 0.1)
				(type default)
			)
			(layer "F.Fab")
		)
		(fp_line
			(start 2.750058 2.750058)
			(end 2.750058 -2.750058)
			(stroke
				(width 0.1)
				(type default)
			)
			(layer "F.Fab")
		)
		(fp_line
			(start -2.750058 -2.750058)
			(end -2.750058 2.750058)
			(stroke
				(width 0.1)
				(type default)
			)
			(layer "F.Fab")
		)
		(fp_line
			(start 2.750058 -2.750058)
			(end -2.750058 -2.750058)
			(stroke
				(width 0.1)
				(type default)
			)
			(layer "F.Fab")
		)
		(pad "1" smd rect
			(at -2.199894 0)
			(size 1.6002 3.0226)
			(layers "F.Cu" "F.Mask" "F.Paste")
			(net "PVDD11_S3_P0")
		)
		(pad "2" smd rect
			(at 2.199894 0)
			(size 1.6002 3.0226)
			(layers "F.Cu" "F.Mask" "F.Paste")
			(net "GND")
		)
	)
)
